(kicad_pcb
	(version 20260206)
	(generator "pcbnew")
	(generator_version "10.0")
	(general
		(thickness 1.6)
		(legacy_teardrops no)
	)
	(paper "A4")
	(title_block
		(title "fcb — 12433-1M.1206WZS1330.brd")
		(comment 1 "Open Vault / Knox (Wiwynn) / footprints 188-192 of 495")
	)
	(layers
		(0 "F.Cu" signal "TOP")
		(4 "In1.Cu" signal "L2GND")
		(6 "In2.Cu" signal "L3VCC")
		(2 "B.Cu" signal "BOTTOM")
		(9 "F.Adhes" user "F.Adhesive")
		(11 "B.Adhes" user "B.Adhesive")
		(13 "F.Paste" user "Package Geometry/Pastemask Top")
		(15 "B.Paste" user "Package Geometry/Pastemask Bottom")
		(5 "F.SilkS" user "Ref Des/Silkscreen Top")
		(7 "B.SilkS" user "Ref Des/Silkscreen Bottom")
		(1 "F.Mask" user "Board Geometry/Soldermask Top")
		(3 "B.Mask" user "Board Geometry/Soldermask Bottom")
		(17 "Dwgs.User" user "User.Drawings")
		(19 "Cmts.User" user "User.Comments")
		(21 "Eco1.User" user "User.Eco1")
		(23 "Eco2.User" user "User.Eco2")
		(25 "Edge.Cuts" user "Board Geometry/Outline")
		(27 "Margin" user)
		(31 "F.CrtYd" user "Package Geometry/Place Bound Top")
		(29 "B.CrtYd" user "Package Geometry/Place Bound Bottom")
		(35 "F.Fab" user "Ref Des/Assembly Top")
		(33 "B.Fab" user "Ref Des/Assembly Bottom")
	)
	(footprint ""
		(layer "F.Cu")
		(at 36.957 -174.244)
		(property "Reference" "PQ9"
			(at 0 0 0)
			(layer "F.SilkS")
			(hide yes)
			(effects
				(font
					(size 1.27 1.27)
				)
			)
		)
		(property "Value" "PMBS3904-1-GP"
			(at 0 -9.0932 0)
			(unlocked yes)
			(layer "F.Fab")
			(hide yes)
			(effects
				(font
					(size 1.016 1.016)
					(thickness 0.1524)
				)
			)
		)
		(property "Device Type" "SOT-23-10H44"
			(at 0 -10.6172 0)
			(unlocked yes)
			(layer "F.Fab")
			(hide yes)
			(effects
				(font
					(size 1.016 1.016)
					(thickness 0.1524)
				)
			)
		)
		(duplicate_pad_numbers_are_jumpers no)
		(fp_line
			(start -1.7526 1.8796)
			(end -1.7526 0.9906)
			(stroke
				(width 0.3302)
				(type default)
			)
			(layer "F.SilkS")
		)
		(fp_line
			(start -1.651 -1.778)
			(end -1.651 1.778)
			(stroke
				(width 0.1524)
				(type default)
			)
			(layer "F.SilkS")
		)
		(fp_line
			(start -1.651 1.778)
			(end 1.651 1.778)
			(stroke
				(width 0.1524)
				(type default)
			)
			(layer "F.SilkS")
		)
		(fp_line
			(start -1.279398 2.152142)
			(end -0.9906 1.86309)
			(stroke
				(width 0.0127)
				(type default)
			)
			(layer "F.SilkS")
		)
		(fp_line
			(start -1.279144 2.15265)
			(end -0.701294 2.15265)
			(stroke
				(width 0.0127)
				(type default)
			)
			(layer "F.SilkS")
		)
		(fp_line
			(start -1.260856 2.1336)
			(end -0.720344 2.1336)
			(stroke
				(width 0.0127)
				(type default)
			)
			(layer "F.SilkS")
		)
		(fp_line
			(start -1.251458 2.124202)
			(end -0.729996 2.124202)
			(stroke
				(width 0.0127)
				(type default)
			)
			(layer "F.SilkS")
		)
		(fp_line
			(start -1.241806 2.11455)
			(end -0.739394 2.11455)
			(stroke
				(width 0.0127)
				(type default)
			)
			(layer "F.SilkS")
		)
		(fp_line
			(start -1.232408 2.105152)
			(end -0.749046 2.105152)
			(stroke
				(width 0.0127)
				(type default)
			)
			(layer "F.SilkS")
		)
		(fp_line
			(start -1.222756 2.0955)
			(end -0.758444 2.0955)
			(stroke
				(width 0.0127)
				(type default)
			)
			(layer "F.SilkS")
		)
		(fp_line
			(start -1.213358 2.086102)
			(end -0.768096 2.086102)
			(stroke
				(width 0.0127)
				(type default)
			)
			(layer "F.SilkS")
		)
		(fp_line
			(start -1.203706 2.07645)
			(end -0.777494 2.07645)
			(stroke
				(width 0.0127)
				(type default)
			)
			(layer "F.SilkS")
		)
		(fp_line
			(start -1.194308 2.067052)
			(end -0.787146 2.067052)
			(stroke
				(width 0.0127)
				(type default)
			)
			(layer "F.SilkS")
		)
		(fp_line
			(start -1.184656 2.0574)
			(end -0.796544 2.0574)
			(stroke
				(width 0.0127)
				(type default)
			)
			(layer "F.SilkS")
		)
		(fp_line
			(start -1.175258 2.048002)
			(end -0.806196 2.048002)
			(stroke
				(width 0.0127)
				(type default)
			)
			(layer "F.SilkS")
		)
		(fp_line
			(start -1.165606 2.03835)
			(end -0.815594 2.03835)
			(stroke
				(width 0.0127)
				(type default)
			)
			(layer "F.SilkS")
		)
		(fp_line
			(start -1.156208 2.028952)
			(end -0.825246 2.028952)
			(stroke
				(width 0.0127)
				(type default)
			)
			(layer "F.SilkS")
		)
		(fp_line
			(start -1.146556 2.0193)
			(end -0.834644 2.0193)
			(stroke
				(width 0.0127)
				(type default)
			)
			(layer "F.SilkS")
		)
		(fp_line
			(start -1.137158 2.009902)
			(end -0.844296 2.009902)
			(stroke
				(width 0.0127)
				(type default)
			)
			(layer "F.SilkS")
		)
		(fp_line
			(start -1.127506 2.00025)
			(end -0.853694 2.00025)
			(stroke
				(width 0.0127)
				(type default)
			)
			(layer "F.SilkS")
		)
		(fp_line
			(start -1.118108 1.990852)
			(end -0.863346 1.990852)
			(stroke
				(width 0.0127)
				(type default)
			)
			(layer "F.SilkS")
		)
		(fp_line
			(start -1.108456 1.9812)
			(end -0.872744 1.9812)
			(stroke
				(width 0.0127)
				(type default)
			)
			(layer "F.SilkS")
		)
		(fp_line
			(start -1.099058 1.971802)
			(end -0.882396 1.971802)
			(stroke
				(width 0.0127)
				(type default)
			)
			(layer "F.SilkS")
		)
		(fp_line
			(start -1.089406 1.96215)
			(end -0.891794 1.96215)
			(stroke
				(width 0.0127)
				(type default)
			)
			(layer "F.SilkS")
		)
		(fp_line
			(start -1.080008 1.952752)
			(end -0.901446 1.952752)
			(stroke
				(width 0.0127)
				(type default)
			)
			(layer "F.SilkS")
		)
		(fp_line
			(start -1.070356 1.9431)
			(end -0.910844 1.9431)
			(stroke
				(width 0.0127)
				(type default)
			)
			(layer "F.SilkS")
		)
		(fp_line
			(start -1.060958 1.933702)
			(end -0.920496 1.933702)
			(stroke
				(width 0.0127)
				(type default)
			)
			(layer "F.SilkS")
		)
		(fp_line
			(start -1.051306 1.92405)
			(end -0.929894 1.92405)
			(stroke
				(width 0.0127)
				(type default)
			)
			(layer "F.SilkS")
		)
		(fp_line
			(start -1.041908 1.914652)
			(end -0.939546 1.914652)
			(stroke
				(width 0.0127)
				(type default)
			)
			(layer "F.SilkS")
		)
		(fp_line
			(start -1.032256 1.905)
			(end -0.948944 1.905)
			(stroke
				(width 0.0127)
				(type default)
			)
			(layer "F.SilkS")
		)
		(fp_line
			(start -1.022858 1.895602)
			(end -0.958596 1.895602)
			(stroke
				(width 0.0127)
				(type default)
			)
			(layer "F.SilkS")
		)
		(fp_line
			(start -1.013206 1.88595)
			(end -0.967994 1.88595)
			(stroke
				(width 0.0127)
				(type default)
			)
			(layer "F.SilkS")
		)
		(fp_line
			(start -1.003808 1.876552)
			(end -0.977646 1.876552)
			(stroke
				(width 0.0127)
				(type default)
			)
			(layer "F.SilkS")
		)
		(fp_line
			(start -0.994156 1.8669)
			(end -0.987044 1.8669)
			(stroke
				(width 0.0127)
				(type default)
			)
			(layer "F.SilkS")
		)
		(fp_line
			(start -0.9906 1.86309)
			(end -0.701294 2.15265)
			(stroke
				(width 0.0127)
				(type default)
			)
			(layer "F.SilkS")
		)
		(fp_line
			(start -0.719074 2.145538)
			(end -1.265936 2.14122)
			(stroke
				(width 0.0127)
				(type default)
			)
			(layer "F.SilkS")
		)
		(fp_line
			(start -0.71628 2.15265)
			(end -1.26492 2.15265)
			(stroke
				(width 0.0127)
				(type default)
			)
			(layer "F.SilkS")
		)
		(fp_line
			(start -0.635 1.8796)
			(end -1.7526 1.8796)
			(stroke
				(width 0.3302)
				(type default)
			)
			(layer "F.SilkS")
		)
		(fp_line
			(start 1.651 -1.778)
			(end -1.651 -1.778)
			(stroke
				(width 0.1524)
				(type default)
			)
			(layer "F.SilkS")
		)
		(fp_line
			(start 1.651 1.778)
			(end 1.651 -1.778)
			(stroke
				(width 0.1524)
				(type default)
			)
			(layer "F.SilkS")
		)
		(fp_poly
			(pts
				(xy -1.285748 2.159) (xy -1.285748 1.8796) (xy -1.778 1.8796) (xy -1.778 -1.8796) (xy 1.778 -1.8796)
				(xy 1.778 1.8796) (xy -0.694944 1.8796) (xy -0.694944 2.159)
			)
			(stroke
				(width 0)
				(type default)
			)
			(fill no)
			(layer "F.CrtYd")
		)
		(fp_poly
			(pts
				(xy -1.285748 2.159) (xy -1.285748 1.8796) (xy -1.778 1.8796) (xy -1.778 -1.8796) (xy 1.778 -1.8796)
				(xy 1.778 1.8796) (xy -0.694944 1.8796) (xy -0.694944 2.159)
			)
			(stroke
				(width 0)
				(type default)
			)
			(fill no)
			(layer "F.Fab")
		)
		(pad "1" smd rect
			(at -0.98425 0.9525)
			(size 0.762 1.143)
			(layers "F.Cu" "F.Mask" "F.Paste")
			(net "TEMP_ALM#_IN")
		)
		(pad "2" smd rect
			(at 0.98425 0.9525)
			(size 0.762 1.143)
			(layers "F.Cu" "F.Mask" "F.Paste")
			(net "GND")
		)
		(pad "3" smd rect
			(at 0 -0.9525)
			(size 0.762 1.143)
			(layers "F.Cu" "F.Mask" "F.Paste")
			(net "TEMP_ALM#_IN_D")
		)
	)
	(footprint ""
		(layer "F.Cu")
		(at 26.416 -111.633)
		(property "Reference" "PQ7"
			(at 0 0 0)
			(layer "F.SilkS")
			(hide yes)
			(effects
				(font
					(size 1.27 1.27)
				)
			)
		)
		(property "Value" "PH0925CL-GP"
			(at -4.2799 -0.4572 0)
			(unlocked yes)
			(layer "F.Fab")
			(hide yes)
			(effects
				(font
					(size 1.016 1.016)
					(thickness 0.1524)
				)
			)
		)
		(property "Device Type" "LFPAK-5PH48-U"
			(at -4.2799 -1.9812 0)
			(unlocked yes)
			(layer "F.Fab")
			(hide yes)
			(effects
				(font
					(size 1.016 1.016)
					(thickness 0.1524)
				)
			)
		)
		(duplicate_pad_numbers_are_jumpers no)
		(fp_line
			(start -2.7559 -6.5532)
			(end -2.7559 1.0668)
			(stroke
				(width 0.1524)
				(type default)
			)
			(layer "F.SilkS")
		)
		(fp_line
			(start -2.7559 1.0668)
			(end 2.7559 1.0668)
			(stroke
				(width 0.1524)
				(type default)
			)
			(layer "F.SilkS")
		)
		(fp_line
			(start -1.7272 1.1684)
			(end -2.1082 1.1684)
			(stroke
				(width 0.3302)
				(type default)
			)
			(layer "F.SilkS")
		)
		(fp_line
			(start 2.7559 -6.5532)
			(end -2.7559 -6.5532)
			(stroke
				(width 0.1524)
				(type default)
			)
			(layer "F.SilkS")
		)
		(fp_line
			(start 2.7559 1.0668)
			(end 2.7559 -6.5532)
			(stroke
				(width 0.1524)
				(type default)
			)
			(layer "F.SilkS")
		)
		(fp_poly
			(pts
				(xy -2.3368 1.5748) (xy -1.905 1.143) (xy -1.4732 1.5748)
			)
			(stroke
				(width 0)
				(type default)
			)
			(fill yes)
			(layer "F.SilkS")
		)
		(fp_poly
			(pts
				(xy -2.5019 -4.02971) (xy -0.3302 -4.02971) (xy -0.3302 -6.30301) (xy -2.5019 -6.30301)
			)
			(stroke
				(width 0)
				(type default)
			)
			(fill yes)
			(layer "F.Paste")
		)
		(fp_poly
			(pts
				(xy -2.5019 -1.09601) (xy -0.3302 -1.09601) (xy -0.3302 -3.36931) (xy -2.5019 -3.36931)
			)
			(stroke
				(width 0)
				(type default)
			)
			(fill yes)
			(layer "F.Paste")
		)
		(fp_poly
			(pts
				(xy 0.3302 -4.02971) (xy 2.5019 -4.02971) (xy 2.5019 -6.30301) (xy 0.3302 -6.30301)
			)
			(stroke
				(width 0)
				(type default)
			)
			(fill yes)
			(layer "F.Paste")
		)
		(fp_poly
			(pts
				(xy 0.3302 -1.09601) (xy 2.5019 -1.09601) (xy 2.5019 -3.36931) (xy 0.3302 -3.36931)
			)
			(stroke
				(width 0)
				(type default)
			)
			(fill yes)
			(layer "F.Paste")
		)
		(fp_rect
			(start -2.4511 0.3048)
			(end 2.4511 -5.6896)
			(stroke
				(width 0)
				(type default)
			)
			(fill no)
			(layer "F.CrtYd")
		)
		(fp_poly
			(pts
				(xy -3.0099 1.3208) (xy -3.0099 -6.8072) (xy 3.0099 -6.8072) (xy 3.0099 -1.016) (xy 2.4511 -1.016)
				(xy 2.4511 -5.6896) (xy -2.4511 -5.6896) (xy -2.4511 0.3048) (xy 2.4511 0.3048) (xy 2.4511 -1.0033)
				(xy 3.0099 -1.0033) (xy 3.0099 1.3208)
			)
			(stroke
				(width 0)
				(type default)
			)
			(fill no)
			(layer "F.CrtYd")
		)
		(fp_rect
			(start -3.0099 1.3208)
			(end 3.0099 -6.8072)
			(stroke
				(width 0)
				(type default)
			)
			(fill no)
			(layer "F.Fab")
		)
		(pad "1" smd rect
			(at -1.905 0)
			(size 0.762 1.6256)
			(layers "F.Cu" "F.Mask" "F.Paste")
			(net "P12VU")
		)
		(pad "2" smd rect
			(at -0.635 0)
			(size 0.762 1.6256)
			(layers "F.Cu" "F.Mask" "F.Paste")
			(net "P12VU")
		)
		(pad "3" smd rect
			(at 0.635 0)
			(size 0.762 1.6256)
			(layers "F.Cu" "F.Mask" "F.Paste")
			(net "P12VU")
		)
		(pad "4" smd rect
			(at 1.905 0)
			(size 0.762 1.6256)
			(layers "F.Cu" "F.Mask" "F.Paste")
			(net "P12VU_2490_GATE_DRV")
		)
		(pad "5" smd rect
			(at 0 -3.69951)
			(size 5.0038 5.207)
			(layers "F.Cu" "F.Mask" "F.Paste")
			(net "P12VU_NET")
		)
	)
	(footprint ""
		(layer "F.Cu")
		(at 40.259 -178.054 180)
		(property "Reference" "R260"
			(at 0 0 180)
			(layer "F.SilkS")
			(hide yes)
			(effects
				(font
					(size 1.27 1.27)
				)
			)
		)
		(property "Value" "47KR2J-2-GP"
			(at 0.064008 -3.993896 180)
			(unlocked yes)
			(layer "F.Fab")
			(hide yes)
			(effects
				(font
					(size 1.016 1.016)
					(thickness 0.1524)
				)
			)
		)
		(property "Device Type" "R402H16"
			(at 0.064008 -5.517896 180)
			(unlocked yes)
			(layer "F.Fab")
			(hide yes)
			(effects
				(font
					(size 1.016 1.016)
					(thickness 0.1524)
				)
			)
		)
		(duplicate_pad_numbers_are_jumpers no)
		(fp_line
			(start 0.508 -0.9398)
			(end -0.508 -0.9398)
			(stroke
				(width 0.1524)
				(type default)
			)
			(layer "F.SilkS")
		)
		(fp_line
			(start -0.508 -0.9398)
			(end -0.508 0.9398)
			(stroke
				(width 0.1524)
				(type default)
			)
			(layer "F.SilkS")
		)
		(fp_rect
			(start -0.508 0.9398)
			(end 0.508 -0.9398)
			(stroke
				(width 0)
				(type default)
			)
			(fill no)
			(layer "F.CrtYd")
		)
		(fp_rect
			(start -0.508 0.9398)
			(end 0.508 -0.9398)
			(stroke
				(width 0)
				(type default)
			)
			(fill no)
			(layer "F.Fab")
		)
		(pad "1" smd custom
			(at 0 -0.4445 180)
			(size 0.1397 0.1397)
			(layers "F.Cu" "F.Mask" "F.Paste")
			(net "P3V3_AUX")
			(options
				(clearance outline)
				(anchor circle)
			)
			(primitives
				(gr_poly
					(pts
						(arc
							(start -0.1778 -0.2794)
							(mid -0.249642 -0.249642)
							(end -0.2794 -0.1778)
						)
						(arc
							(start -0.2794 0.1778)
							(mid -0.249642 0.249642)
							(end -0.1778 0.2794)
						)
						(arc
							(start 0.1778 0.2794)
							(mid 0.249642 0.249642)
							(end 0.2794 0.1778)
						)
						(arc
							(start 0.2794 -0.1778)
							(mid 0.249642 -0.249642)
							(end 0.1778 -0.2794)
						)
					)
					(width 0)
					(fill yes)
				)
			)
		)
		(pad "2" smd custom
			(at 0 0.4445 180)
			(size 0.1397 0.1397)
			(layers "F.Cu" "F.Mask" "F.Paste")
			(net "D_LATCH_PRE#")
			(options
				(clearance outline)
				(anchor circle)
			)
			(primitives
				(gr_poly
					(pts
						(arc
							(start -0.1778 -0.2794)
							(mid -0.249642 -0.249642)
							(end -0.2794 -0.1778)
						)
						(arc
							(start -0.2794 0.1778)
							(mid -0.249642 0.249642)
							(end -0.1778 0.2794)
						)
						(arc
							(start 0.1778 0.2794)
							(mid 0.249642 0.249642)
							(end 0.2794 0.1778)
						)
						(arc
							(start 0.2794 -0.1778)
							(mid 0.249642 -0.249642)
							(end 0.1778 -0.2794)
						)
					)
					(width 0)
					(fill yes)
				)
			)
		)
	)
	(footprint ""
		(layer "F.Cu")
		(at 19.558508 -288.594038)
		(property "Reference" "R103"
			(at 0 0 0)
			(layer "F.SilkS")
			(hide yes)
			(effects
				(font
					(size 1.27 1.27)
				)
			)
		)
		(property "Value" "10KR2F-2-GP"
			(at 0.064008 -3.993896 0)
			(unlocked yes)
			(layer "F.Fab")
			(hide yes)
			(effects
				(font
					(size 1.016 1.016)
					(thickness 0.1524)
				)
			)
		)
		(property "Device Type" "R402H16"
			(at 0.064008 -5.517896 0)
			(unlocked yes)
			(layer "F.Fab")
			(hide yes)
			(effects
				(font
					(size 1.016 1.016)
					(thickness 0.1524)
				)
			)
		)
		(duplicate_pad_numbers_are_jumpers no)
		(fp_line
			(start -0.508 -0.9398)
			(end -0.508 0.9398)
			(stroke
				(width 0.1524)
				(type default)
			)
			(layer "F.SilkS")
		)
		(fp_line
			(start 0.508 -0.9398)
			(end -0.508 -0.9398)
			(stroke
				(width 0.1524)
				(type default)
			)
			(layer "F.SilkS")
		)
		(fp_rect
			(start -0.508 0.9398)
			(end 0.508 -0.9398)
			(stroke
				(width 0)
				(type default)
			)
			(fill no)
			(layer "F.CrtYd")
		)
		(fp_rect
			(start -0.508 0.9398)
			(end 0.508 -0.9398)
			(stroke
				(width 0)
				(type default)
			)
			(fill no)
			(layer "F.Fab")
		)
		(pad "1" smd custom
			(at 0 -0.4445)
			(size 0.1397 0.1397)
			(layers "F.Cu" "F.Mask" "F.Paste")
			(net "FANIN_4")
			(options
				(clearance outline)
				(anchor circle)
			)
			(primitives
				(gr_poly
					(pts
						(arc
							(start -0.1778 -0.2794)
							(mid -0.249642 -0.249642)
							(end -0.2794 -0.1778)
						)
						(arc
							(start -0.2794 0.1778)
							(mid -0.249642 0.249642)
							(end -0.1778 0.2794)
						)
						(arc
							(start 0.1778 0.2794)
							(mid 0.249642 0.249642)
							(end 0.2794 0.1778)
						)
						(arc
							(start 0.2794 -0.1778)
							(mid 0.249642 -0.249642)
							(end 0.1778 -0.2794)
						)
					)
					(width 0)
					(fill yes)
				)
			)
		)
		(pad "2" smd custom
			(at 0 0.4445)
			(size 0.1397 0.1397)
			(layers "F.Cu" "F.Mask" "F.Paste")
			(net "GND")
			(options
				(clearance outline)
				(anchor circle)
			)
			(primitives
				(gr_poly
					(pts
						(arc
							(start -0.1778 -0.2794)
							(mid -0.249642 -0.249642)
							(end -0.2794 -0.1778)
						)
						(arc
							(start -0.2794 0.1778)
							(mid -0.249642 0.249642)
							(end -0.1778 0.2794)
						)
						(arc
							(start 0.1778 0.2794)
							(mid 0.249642 0.249642)
							(end 0.2794 0.1778)
						)
						(arc
							(start 0.2794 -0.1778)
							(mid 0.249642 -0.249642)
							(end 0.1778 -0.2794)
						)
					)
					(width 0)
					(fill yes)
				)
			)
		)
	)
	(footprint ""
		(layer "F.Cu")
		(at 26.67 -361.188)
		(property "Reference" "PR116"
			(at 0 0 0)
			(layer "F.SilkS")
			(hide yes)
			(effects
				(font
					(size 1.27 1.27)
				)
			)
		)
		(property "Value" "0R2J-2-GP"
			(at 0.064008 -3.993896 0)
			(unlocked yes)
			(layer "F.Fab")
			(hide yes)
			(effects
				(font
					(size 1.016 1.016)
					(thickness 0.1524)
				)
			)
		)
		(property "Device Type" "R402H16"
			(at 0.064008 -5.517896 0)
			(unlocked yes)
			(layer "F.Fab")
			(hide yes)
			(effects
				(font
					(size 1.016 1.016)
					(thickness 0.1524)
				)
			)
		)
		(duplicate_pad_numbers_are_jumpers no)
		(fp_line
			(start -0.508 -0.9398)
			(end -0.508 0.9398)
			(stroke
				(width 0.1524)
				(type default)
			)
			(layer "F.SilkS")
		)
		(fp_line
			(start 0.508 -0.9398)
			(end -0.508 -0.9398)
			(stroke
				(width 0.1524)
				(type default)
			)
			(layer "F.SilkS")
		)
		(fp_rect
			(start -0.508 0.9398)
			(end 0.508 -0.9398)
			(stroke
				(width 0)
				(type default)
			)
			(fill no)
			(layer "F.CrtYd")
		)
		(fp_rect
			(start -0.508 0.9398)
			(end 0.508 -0.9398)
			(stroke
				(width 0)
				(type default)
			)
			(fill no)
			(layer "F.Fab")
		)
		(pad "1" smd custom
			(at 0 -0.4445)
			(size 0.1397 0.1397)
			(layers "F.Cu" "F.Mask" "F.Paste")
			(net "ADM1276_LATCH#")
			(options
				(clearance outline)
				(anchor circle)
			)
			(primitives
				(gr_poly
					(pts
						(arc
							(start -0.1778 -0.2794)
							(mid -0.249642 -0.249642)
							(end -0.2794 -0.1778)
						)
						(arc
							(start -0.2794 0.1778)
							(mid -0.249642 0.249642)
							(end -0.1778 0.2794)
						)
						(arc
							(start 0.1778 0.2794)
							(mid 0.249642 0.249642)
							(end 0.2794 0.1778)
						)
						(arc
							(start 0.2794 -0.1778)
							(mid 0.249642 -0.249642)
							(end 0.1778 -0.2794)
						)
					)
					(width 0)
					(fill yes)
				)
			)
		)
		(pad "2" smd custom
			(at 0 0.4445)
			(size 0.1397 0.1397)
			(layers "F.Cu" "F.Mask" "F.Paste")
			(net "P3V3")
			(options
				(clearance outline)
				(anchor circle)
			)
			(primitives
				(gr_poly
					(pts
						(arc
							(start -0.1778 -0.2794)
							(mid -0.249642 -0.249642)
							(end -0.2794 -0.1778)
						)
						(arc
							(start -0.2794 0.1778)
							(mid -0.249642 0.249642)
							(end -0.1778 0.2794)
						)
						(arc
							(start 0.1778 0.2794)
							(mid 0.249642 0.249642)
							(end 0.2794 0.1778)
						)
						(arc
							(start 0.2794 -0.1778)
							(mid 0.249642 -0.249642)
							(end 0.1778 -0.2794)
						)
					)
					(width 0)
					(fill yes)
				)
			)
		)
	)
)
